# S9S_MB_2U (Grand Teton) — schematic netlist excerpt (pin names and nets, part order shuffled) for the footprints in the layout excerpt that follows; sources: Cadence DE-HDL packaged netlist, KiCad conversion of 03242023_DA0F0TMBIJ0_F0T_Motherboard_J_brd_V01_OCP.brd

R1194  Q_RES  4.75K 1% EMPTY  pkg 0402LF  page 208 : A = P3V3_AUX ; B = FM_CK440_MXCK_25M_100M
R4546  Q_RES  4.7K 5% EMPTY  pkg 0402LF  page 145 : A = P3V3_AUX ; B = HGX_DETECT_N_ISO

(kicad_pcb
	(version 20260206)
	(generator "pcbnew")
	(generator_version "10.0")
	(general
		(thickness 1.6)
		(legacy_teardrops no)
	)
	(paper "A4")
	(title_block
		(title "03242023_DA0F0TMBIJ0_F0T_Motherboard_J_brd_V01_OCP.brd")
		(comment 1 "Grand Teton / footprints 5943-5944 of 6105")
	)
	(layers
		(0 "F.Cu" signal "TOP")
		(4 "In1.Cu" signal "GND")
		(6 "In2.Cu" signal "IN1")
		(8 "In3.Cu" signal "GND1")
		(10 "In4.Cu" signal "IN2")
		(12 "In5.Cu" signal "GND2")
		(14 "In6.Cu" signal "IN3")
		(16 "In7.Cu" signal "GND3")
		(18 "In8.Cu" signal "VCC")
		(20 "In9.Cu" signal "VCC1")
		(22 "In10.Cu" signal "GND4")
		(24 "In11.Cu" signal "IN4")
		(26 "In12.Cu" signal "GND5")
		(28 "In13.Cu" signal "IN5")
		(30 "In14.Cu" signal "GND6")
		(32 "In15.Cu" signal "IN6")
		(34 "In16.Cu" signal "GND7")
		(2 "B.Cu" signal "BOTTOM")
		(9 "F.Adhes" user "F.Adhesive")
		(11 "B.Adhes" user "B.Adhesive")
		(13 "F.Paste" user "Package Geometry/Pastemask Top")
		(15 "B.Paste" user "Package Geometry/Pastemask Bottom")
		(5 "F.SilkS" user "Ref Des/Silkscreen Top")
		(7 "B.SilkS" user "Ref Des/Silkscreen Bottom")
		(1 "F.Mask" user "Board Geometry/Soldermask Top")
		(3 "B.Mask" user "Board Geometry/Soldermask Bottom")
		(17 "Dwgs.User" user "User.Drawings")
		(19 "Cmts.User" user "User.Comments")
		(21 "Eco1.User" user "User.Eco1")
		(23 "Eco2.User" user "User.Eco2")
		(25 "Edge.Cuts" user "Board Geometry/Outline")
		(27 "Margin" user)
		(31 "F.CrtYd" user "Package Geometry/Place Bound Top")
		(29 "B.CrtYd" user "Package Geometry/Place Bound Bottom")
		(35 "F.Fab" user "Ref Des/Assembly Top")
		(33 "B.Fab" user "Ref Des/Assembly Bottom")
	)
	(footprint ""
		(layer "B.Cu")
		(at 98.50374 -422.156128 90)
		(property "Reference" "R4546"
			(at 0 0 90)
			(layer "B.SilkS")
			(hide yes)
			(effects
				(font
					(size 1.27 1.27)
				)
				(justify mirror)
			)
		)
		(property "Value" ""
			(at 0 0 90)
			(layer "B.Fab")
			(effects
				(font
					(size 1.27 1.27)
				)
				(justify mirror)
			)
		)
		(duplicate_pad_numbers_are_jumpers no)
		(fp_line
			(start 0.7874 -0.4064)
			(end -0.7874 -0.4064)
			(stroke
				(width 0.1524)
				(type default)
			)
			(layer "B.SilkS")
		)
		(fp_line
			(start -0.7874 -0.4064)
			(end -0.7874 0.4064)
			(stroke
				(width 0.1524)
				(type default)
			)
			(layer "B.SilkS")
		)
		(fp_line
			(start 0.7874 0.4064)
			(end 0.7874 -0.4064)
			(stroke
				(width 0.1524)
				(type default)
			)
			(layer "B.SilkS")
		)
		(fp_line
			(start -0.7874 0.4064)
			(end 0.7874 0.4064)
			(stroke
				(width 0.1524)
				(type default)
			)
			(layer "B.SilkS")
		)
		(fp_line
			(start 0.67945 -0.305054)
			(end 0.12065 -0.305054)
			(stroke
				(width 0.1)
				(type default)
			)
			(layer "B.Fab")
		)
		(fp_line
			(start 0.12065 -0.305054)
			(end 0.12065 -0.2794)
			(stroke
				(width 0.1)
				(type default)
			)
			(layer "B.Fab")
		)
		(fp_line
			(start -0.12065 -0.3048)
			(end -0.67945 -0.3048)
			(stroke
				(width 0.1)
				(type default)
			)
			(layer "B.Fab")
		)
		(fp_line
			(start -0.67945 -0.3048)
			(end -0.67945 0.3048)
			(stroke
				(width 0.1)
				(type default)
			)
			(layer "B.Fab")
		)
		(fp_line
			(start 0.12065 -0.2794)
			(end -0.12065 -0.2794)
			(stroke
				(width 0.1)
				(type default)
			)
			(layer "B.Fab")
		)
		(fp_line
			(start -0.12065 -0.2794)
			(end -0.12065 -0.3048)
			(stroke
				(width 0.1)
				(type default)
			)
			(layer "B.Fab")
		)
		(fp_line
			(start 0.12065 0.2794)
			(end 0.12065 0.3048)
			(stroke
				(width 0.1)
				(type default)
			)
			(layer "B.Fab")
		)
		(fp_line
			(start -0.120396 0.2794)
			(end 0.12065 0.2794)
			(stroke
				(width 0.1)
				(type default)
			)
			(layer "B.Fab")
		)
		(fp_line
			(start 0.67945 0.3048)
			(end 0.67945 -0.305054)
			(stroke
				(width 0.1)
				(type default)
			)
			(layer "B.Fab")
		)
		(fp_line
			(start 0.12065 0.3048)
			(end 0.67945 0.3048)
			(stroke
				(width 0.1)
				(type default)
			)
			(layer "B.Fab")
		)
		(fp_line
			(start -0.120396 0.3048)
			(end -0.120396 0.2794)
			(stroke
				(width 0.1)
				(type default)
			)
			(layer "B.Fab")
		)
		(fp_line
			(start -0.67945 0.3048)
			(end -0.120396 0.3048)
			(stroke
				(width 0.1)
				(type default)
			)
			(layer "B.Fab")
		)
		(pad "1" smd circle
			(at 0.40005 0 270)
			(size 0 0)
			(layers "B.Cu" "B.Mask" "B.Paste")
			(net "P3V3_AUX")
		)
		(pad "2" smd circle
			(at -0.40005 0 270)
			(size 0 0)
			(layers "B.Cu" "B.Mask" "B.Paste")
			(net "HGX_DETECT_N_ISO")
		)
	)
	(footprint ""
		(layer "B.Cu")
		(at 258.384802 -105.911396)
		(property "Reference" "R1194"
			(at 0 0 0)
			(layer "B.SilkS")
			(hide yes)
			(effects
				(font
					(size 1.27 1.27)
				)
				(justify mirror)
			)
		)
		(property "Value" ""
			(at 0 0 0)
			(layer "B.Fab")
			(effects
				(font
					(size 1.27 1.27)
				)
				(justify mirror)
			)
		)
		(duplicate_pad_numbers_are_jumpers no)
		(fp_line
			(start -0.7874 -0.4064)
			(end -0.7874 0.4064)
			(stroke
				(width 0.1524)
				(type default)
			)
			(layer "B.SilkS")
		)
		(fp_line
			(start -0.7874 0.4064)
			(end 0.7874 0.4064)
			(stroke
				(width 0.1524)
				(type default)
			)
			(layer "B.SilkS")
		)
		(fp_line
			(start 0.7874 -0.4064)
			(end -0.7874 -0.4064)
			(stroke
				(width 0.1524)
				(type default)
			)
			(layer "B.SilkS")
		)
		(fp_line
			(start 0.7874 0.4064)
			(end 0.7874 -0.4064)
			(stroke
				(width 0.1524)
				(type default)
			)
			(layer "B.SilkS")
		)
		(fp_line
			(start -0.67945 -0.3048)
			(end -0.67945 0.3048)
			(stroke
				(width 0.1)
				(type default)
			)
			(layer "B.Fab")
		)
		(fp_line
			(start -0.67945 0.3048)
			(end -0.120396 0.3048)
			(stroke
				(width 0.1)
				(type default)
			)
			(layer "B.Fab")
		)
		(fp_line
			(start -0.12065 -0.3048)
			(end -0.67945 -0.3048)
			(stroke
				(width 0.1)
				(type default)
			)
			(layer "B.Fab")
		)
		(fp_line
			(start -0.12065 -0.2794)
			(end -0.12065 -0.3048)
			(stroke
				(width 0.1)
				(type default)
			)
			(layer "B.Fab")
		)
		(fp_line
			(start -0.120396 0.2794)
			(end 0.12065 0.2794)
			(stroke
				(width 0.1)
				(type default)
			)
			(layer "B.Fab")
		)
		(fp_line
			(start -0.120396 0.3048)
			(end -0.120396 0.2794)
			(stroke
				(width 0.1)
				(type default)
			)
			(layer "B.Fab")
		)
		(fp_line
			(start 0.12065 -0.305054)
			(end 0.12065 -0.2794)
			(stroke
				(width 0.1)
				(type default)
			)
			(layer "B.Fab")
		)
		(fp_line
			(start 0.12065 -0.2794)
			(end -0.12065 -0.2794)
			(stroke
				(width 0.1)
				(type default)
			)
			(layer "B.Fab")
		)
		(fp_line
			(start 0.12065 0.2794)
			(end 0.12065 0.3048)
			(stroke
				(width 0.1)
				(type default)
			)
			(layer "B.Fab")
		)
		(fp_line
			(start 0.12065 0.3048)
			(end 0.67945 0.3048)
			(stroke
				(width 0.1)
				(type default)
			)
			(layer "B.Fab")
		)
		(fp_line
			(start 0.67945 -0.305054)
			(end 0.12065 -0.305054)
			(stroke
				(width 0.1)
				(type default)
			)
			(layer "B.Fab")
		)
		(fp_line
			(start 0.67945 0.3048)
			(end 0.67945 -0.305054)
			(stroke
				(width 0.1)
				(type default)
			)
			(layer "B.Fab")
		)
		(pad "1" smd circle
			(at 0.40005 0 180)
			(size 0 0)
			(layers "B.Cu" "B.Mask" "B.Paste")
			(net "P3V3_AUX")
		)
		(pad "2" smd circle
			(at -0.40005 0 180)
			(size 0 0)
			(layers "B.Cu" "B.Mask" "B.Paste")
			(net "FM_CK440_MXCK_25M_100M")
		)
	)
)
